# TIMECARD (Time Appliance Project (Time Card)) — schematic netlist excerpt (pin names and nets, part order shuffled) for the footprints in the layout excerpt that follows; sources: Cadence DE-HDL packaged netlist, KiCad conversion of R4006-B0001-02_R01.brd

TP41  TP_PIONT  pkg TP010CT020B030_PTH  page 25 : \1\ = XP1R8V_FPGA_PG
R406  RESISTOR  33OHM 1%  pkg SMC_0402R_H016  page 17 : \1\ = LM75B_I2C_SDA ; \2\ = R_LM75B_2_I2C_SDA
MAC_PIN8  NUT  pkg P_NUT_079C100  page 21 : \1\ = R_MAC_UART_RX_FPGA_TX

(kicad_pcb
	(version 20260206)
	(generator "pcbnew")
	(generator_version "10.0")
	(general
		(thickness 1.6)
		(legacy_teardrops no)
	)
	(paper "A4")
	(title_block
		(title "timecard-production-celestica-r4006 — R4006-B0001-02_R01.brd")
		(comment 1 "Time Appliance Project (Time Card) / footprints 361-363 of 1113")
	)
	(layers
		(0 "F.Cu" signal "TOP")
		(4 "In1.Cu" signal "L02_GND1")
		(6 "In2.Cu" signal "L03_SIG1")
		(8 "In3.Cu" signal "L04_GND2")
		(10 "In4.Cu" signal "L05_VCC1")
		(12 "In5.Cu" signal "L06_VCC2")
		(14 "In6.Cu" signal "L07_GND3")
		(16 "In7.Cu" signal "L08_SIG2")
		(18 "In8.Cu" signal "L09_GND4")
		(2 "B.Cu" signal "BOTTOM")
		(9 "F.Adhes" user "F.Adhesive")
		(11 "B.Adhes" user "B.Adhesive")
		(13 "F.Paste" user "Package Geometry/Pastemask Top")
		(15 "B.Paste" user "Package Geometry/Pastemask Bottom")
		(5 "F.SilkS" user "Ref Des/Silkscreen Top")
		(7 "B.SilkS" user "Ref Des/Silkscreen Bottom")
		(1 "F.Mask" user "Board Geometry/Soldermask Top")
		(3 "B.Mask" user "Board Geometry/Soldermask Bottom")
		(17 "Dwgs.User" user "User.Drawings")
		(19 "Cmts.User" user "User.Comments")
		(21 "Eco1.User" user "User.Eco1")
		(23 "Eco2.User" user "User.Eco2")
		(25 "Edge.Cuts" user "Board Geometry/Outline")
		(27 "Margin" user)
		(31 "F.CrtYd" user "Package Geometry/Place Bound Top")
		(29 "B.CrtYd" user "Package Geometry/Place Bound Bottom")
		(35 "F.Fab" user "Ref Des/Assembly Top")
		(33 "B.Fab" user "Ref Des/Assembly Bottom")
	)
	(footprint ""
		(layer "F.Cu")
		(at 57.47512 -82.9564 90)
		(property "Reference" "R406"
			(at 0.2286 1.11125 90)
			(unlocked yes)
			(layer "F.SilkS")
			(effects
				(font
					(size 0.7874 0.5842)
					(thickness 0.1524)
				)
			)
		)
		(property "Value" "VAL*"
			(at 0.02032 2.13233 90)
			(unlocked yes)
			(layer "F.Fab")
			(hide yes)
			(effects
				(font
					(size 0.7874 0.5842)
					(thickness 0.1524)
				)
			)
		)
		(property "Device Type" "RESISTOR-G155-133R0-01,33OHM,1%"
			(at 0.008382 1.210564 90)
			(unlocked yes)
			(layer "F.Fab")
			(hide yes)
			(effects
				(font
					(size 0.7874 0.5842)
					(thickness 0.1524)
				)
			)
		)
		(property "User Part Number" "PARTNUM*"
			(at 0.02032 4.024884 90)
			(unlocked yes)
			(layer "Cmts.User")
			(hide yes)
			(effects
				(font
					(size 0.7874 0.5842)
					(thickness 0.1524)
				)
			)
		)
		(property "Tolerance" "TOL*"
			(at 0.044704 3.05435 90)
			(unlocked yes)
			(layer "Cmts.User")
			(hide yes)
			(effects
				(font
					(size 0.7874 0.5842)
					(thickness 0.1524)
				)
			)
		)
		(duplicate_pad_numbers_are_jumpers no)
		(fp_line
			(start 1.143 -0.5588)
			(end -1.143 -0.5588)
			(stroke
				(width 0.1)
				(type default)
			)
			(layer "F.SilkS")
		)
		(fp_line
			(start -1.143 -0.5588)
			(end -1.143 0.5588)
			(stroke
				(width 0.1)
				(type default)
			)
			(layer "F.SilkS")
		)
		(fp_line
			(start 1.143 0.5588)
			(end 1.143 -0.5588)
			(stroke
				(width 0.1)
				(type default)
			)
			(layer "F.SilkS")
		)
		(fp_line
			(start -1.143 0.5588)
			(end 1.143 0.5588)
			(stroke
				(width 0.1)
				(type default)
			)
			(layer "F.SilkS")
		)
		(fp_rect
			(start -1.143 0.5588)
			(end 1.143 -0.5588)
			(stroke
				(width 0)
				(type default)
			)
			(fill no)
			(layer "F.CrtYd")
		)
		(fp_line
			(start 0.508 -0.3048)
			(end -0.508 -0.3048)
			(stroke
				(width 0.1)
				(type default)
			)
			(layer "F.Fab")
		)
		(fp_line
			(start -0.508 -0.3048)
			(end -0.508 0.3048)
			(stroke
				(width 0.1)
				(type default)
			)
			(layer "F.Fab")
		)
		(fp_line
			(start 0.508 0.3048)
			(end 0.508 -0.3048)
			(stroke
				(width 0.1)
				(type default)
			)
			(layer "F.Fab")
		)
		(fp_line
			(start -0.508 0.3048)
			(end 0.508 0.3048)
			(stroke
				(width 0.1)
				(type default)
			)
			(layer "F.Fab")
		)
		(pad "1" smd rect
			(at -0.5334 0 90)
			(size 0.7112 0.6096)
			(layers "F.Cu" "F.Mask" "F.Paste")
			(net "LM75B_I2C_SDA")
		)
		(pad "2" smd rect
			(at 0.5334 0 90)
			(size 0.7112 0.6096)
			(layers "F.Cu" "F.Mask" "F.Paste")
			(net "R_LM75B_2_I2C_SDA")
		)
		(zone
			(layer "F.Cu")
			(hatch none 0.5)
			(connect_pads
				(clearance 0)
			)
			(min_thickness 0.25)
			(keepout
				(tracks allowed)
				(vias not_allowed)
				(pads allowed)
				(copperpour not_allowed)
				(footprints allowed)
			)
			(placement
				(enabled no)
				(sheetname "")
			)
			(fill
				(thermal_gap 0.5)
				(thermal_bridge_width 0.5)
				(island_removal_mode 0)
			)
			(polygon
				(pts
					(xy 57.77992 -82.8802) (xy 57.77992 -83.0326) (xy 57.17032 -83.0326) (xy 57.17032 -82.8802)
				)
			)
		)
		(zone
			(layer "F.Cu")
			(hatch none 0.5)
			(connect_pads
				(clearance 0)
			)
			(min_thickness 0.25)
			(keepout
				(tracks not_allowed)
				(vias allowed)
				(pads allowed)
				(copperpour not_allowed)
				(footprints allowed)
			)
			(placement
				(enabled no)
				(sheetname "")
			)
			(fill
				(thermal_gap 0.5)
				(thermal_bridge_width 0.5)
				(island_removal_mode 0)
			)
			(polygon
				(pts
					(xy 57.77992 -82.8802) (xy 57.77992 -83.0326) (xy 57.17032 -83.0326) (xy 57.17032 -82.8802)
				)
			)
		)
	)
	(footprint ""
		(layer "F.Cu")
		(at 64.507618 -23.734522)
		(property "Reference" "MAC_PIN8"
			(at -3.936238 2.580132 0)
			(unlocked yes)
			(layer "F.SilkS")
			(effects
				(font
					(size 0.7874 0.5842)
					(thickness 0.1524)
				)
			)
		)
		(property "Value" ""
			(at 0 0 0)
			(layer "F.Fab")
			(effects
				(font
					(size 1.27 1.27)
				)
			)
		)
		(property "Device Type" "NUT-A200-00029-FB"
			(at 0 2.632964 0)
			(unlocked yes)
			(layer "F.Fab")
			(hide yes)
			(effects
				(font
					(size 0.7874 0.5842)
					(thickness 0.1524)
				)
			)
		)
		(property "User Part Number" "PARTNUM*"
			(at 0 3.826764 0)
			(unlocked yes)
			(layer "Cmts.User")
			(hide yes)
			(effects
				(font
					(size 0.7874 0.5842)
					(thickness 0.1524)
				)
			)
		)
		(duplicate_pad_numbers_are_jumpers no)
		(fp_circle
			(center 0 0)
			(end 1.524 0)
			(stroke
				(width 0.1)
				(type default)
			)
			(fill no)
			(layer "F.SilkS")
		)
		(fp_poly
			(pts
				(arc
					(start -1.260856 -0.1524)
					(mid -0.898049 -0.898049)
					(end -0.1524 -1.260856)
				)
				(arc
					(start -0.1524 -0.991616)
					(mid -0.709411 -0.709411)
					(end -0.991616 -0.1524)
				)
			)
			(stroke
				(width 0)
				(type default)
			)
			(fill yes)
			(layer "F.Paste")
		)
		(fp_poly
			(pts
				(arc
					(start -0.1524 1.260856)
					(mid -0.898049 0.898049)
					(end -1.260856 0.1524)
				)
				(arc
					(start -0.991616 0.1524)
					(mid -0.709411 0.709411)
					(end -0.1524 0.991616)
				)
			)
			(stroke
				(width 0)
				(type default)
			)
			(fill yes)
			(layer "F.Paste")
		)
		(fp_poly
			(pts
				(arc
					(start 0.1524 -1.260856)
					(mid 0.898049 -0.898049)
					(end 1.260856 -0.1524)
				)
				(arc
					(start 0.991616 -0.1524)
					(mid 0.709411 -0.709411)
					(end 0.1524 -0.991616)
				)
			)
			(stroke
				(width 0)
				(type default)
			)
			(fill yes)
			(layer "F.Paste")
		)
		(fp_poly
			(pts
				(arc
					(start 1.260856 0.1524)
					(mid 0.898049 0.898049)
					(end 0.1524 1.260856)
				)
				(arc
					(start 0.1524 0.991616)
					(mid 0.709411 0.709411)
					(end 0.991616 0.1524)
				)
			)
			(stroke
				(width 0)
				(type default)
			)
			(fill yes)
			(layer "F.Paste")
		)
		(fp_poly
			(pts
				(arc
					(start 6.35 0)
					(mid -6.35 0)
					(end 6.35 0)
				)
			)
			(stroke
				(width 0)
				(type default)
			)
			(fill no)
			(layer "B.CrtYd")
		)
		(fp_poly
			(pts
				(arc
					(start 1.778 0)
					(mid -1.778 0)
					(end 1.778 0)
				)
			)
			(stroke
				(width 0)
				(type default)
			)
			(fill no)
			(layer "F.CrtYd")
		)
		(fp_circle
			(center 0 0)
			(end 1.1684 0)
			(stroke
				(width 0.1)
				(type default)
			)
			(fill no)
			(layer "F.Fab")
		)
		(pad "1" thru_hole circle
			(at 0 0)
			(size 2.54 2.54)
			(drill 2.0066)
			(layers "*.Cu" "*.Mask")
			(remove_unused_layers no)
			(net "R_MAC_UART_RX_FPGA_TX")
			(thermal_gap 0.0254)
			(padstack
				(mode front_inner_back)
				(layer "Inner"
					(shape circle)
					(size 2.54 2.54)
					(clearance 0.0254)
				)
				(layer "B.Cu"
					(shape circle)
					(size 2.54 2.54)
				)
			)
		)
	)
	(footprint ""
		(layer "F.Cu")
		(at 146.431 -24.892)
		(property "Reference" "TP41"
			(at -0.7112 0.92837 0)
			(unlocked yes)
			(layer "F.SilkS")
			(effects
				(font
					(size 0.7874 0.5842)
					(thickness 0.1524)
				)
				(justify left)
			)
		)
		(property "Value" ""
			(at 0 0 0)
			(layer "F.Fab")
			(effects
				(font
					(size 1.27 1.27)
				)
			)
		)
		(property "Device Type" "TP_PIONT-TP010CT020B030_PTH-TPA"
			(at -1.341882 0.996696 0)
			(unlocked yes)
			(layer "F.Fab")
			(hide yes)
			(effects
				(font
					(size 0.7874 0.5842)
					(thickness 0.000001)
				)
				(justify left)
			)
		)
		(duplicate_pad_numbers_are_jumpers no)
		(fp_poly
			(pts
				(arc
					(start 0.889 0)
					(mid -0.889 0)
					(end 0.889 0)
				)
			)
			(stroke
				(width 0)
				(type default)
			)
			(fill no)
			(layer "B.CrtYd")
		)
		(fp_poly
			(pts
				(arc
					(start 0.889 0)
					(mid -0.889 0)
					(end 0.889 0)
				)
			)
			(stroke
				(width 0)
				(type default)
			)
			(fill no)
			(layer "F.CrtYd")
		)
		(pad "1" thru_hole circle
			(at 0 0)
			(size 0.508 0.508)
			(drill 0.254)
			(layers "*.Cu" "*.Mask")
			(remove_unused_layers no)
			(net "XP1R8V_FPGA_PG")
			(clearance 0.1016)
			(padstack
				(mode front_inner_back)
				(layer "Inner"
					(shape circle)
					(size 0.508 0.508)
					(clearance 0.1016)
				)
				(layer "B.Cu"
					(shape circle)
					(size 0.762 0.762)
					(clearance -0.0254)
				)
			)
		)
	)
)
